(kicad_pcb
	(version 20241229)
	(generator "pcbnew")
	(generator_version "9.0")
	(general
		(thickness 1.62)
		(legacy_teardrops no)
	)
	(paper "A4")
	(title_block
		(title "OCuLink to 10GbE adapter")
		(date "2026-02-23")
		(rev "1.1.0")
		(company "Antmicro Ltd")
		(comment 1 "www.antmicro.com")
		(comment 9 "footprints 63-67 of 510")
	)
	(layers
		(0 "F.Cu" signal)
		(4 "In1.Cu" signal)
		(6 "In2.Cu" signal)
		(8 "In3.Cu" signal)
		(10 "In4.Cu" signal)
		(12 "In5.Cu" signal)
		(14 "In6.Cu" signal)
		(2 "B.Cu" signal)
		(9 "F.Adhes" user "F.Adhesive")
		(11 "B.Adhes" user "B.Adhesive")
		(13 "F.Paste" user)
		(15 "B.Paste" user)
		(5 "F.SilkS" user "F.Silkscreen")
		(7 "B.SilkS" user "B.Silkscreen")
		(1 "F.Mask" user)
		(3 "B.Mask" user)
		(17 "Dwgs.User" user "User.Drawings")
		(19 "Cmts.User" user "User.Comments")
		(21 "Eco1.User" user "User.Eco1")
		(23 "Eco2.User" user "User.Eco2")
		(25 "Edge.Cuts" user)
		(27 "Margin" user)
		(31 "F.CrtYd" user "F.Courtyard")
		(29 "B.CrtYd" user "B.Courtyard")
		(35 "F.Fab" user)
		(33 "B.Fab" user)
	)
	(footprint "antmicro-footprints:C_0402_1005Metric"
		(layer "F.Cu")
		(at 55.1 108.249996 90)
		(descr "Capacitor SMD 0402")
		(tags "capacitor SMD 0402")
		(property "Reference" "C29"
			(at -1.100004 -2.34 90)
			(layer "F.SilkS")
			(effects
				(font
					(size 0.7 0.7)
					(thickness 0.15)
				)
				(justify left bottom)
			)
		)
		(property "Value" "C_33p_0402"
			(at -1.022927 2.155213 90)
			(layer "F.Fab")
			(hide yes)
			(effects
				(font
					(size 0.7 0.7)
					(thickness 0.15)
				)
				(justify left bottom)
			)
		)
		(property "Datasheet" "https://spicat.kyocera-avx.com/product/mlcc/chartview/04025A330FAT2A/"
			(at 0 0 90)
			(layer "F.Fab")
			(hide yes)
			(effects
				(font
					(size 1.27 1.27)
					(thickness 0.15)
				)
			)
		)
		(property "Description" "SMD Multilayer Ceramic Capacitor, 33 pF, 50 V, 0402 [1005 Metric], ± 5%, C0G / NP0, MC"
			(at 0 0 90)
			(layer "F.Fab")
			(hide yes)
			(effects
				(font
					(size 1.27 1.27)
					(thickness 0.15)
				)
			)
		)
		(property "MPN" "04025A330FAT2A"
			(at 0 0 90)
			(unlocked yes)
			(layer "F.Fab")
			(hide yes)
			(effects
				(font
					(size 1 1)
					(thickness 0.15)
				)
			)
		)
		(property "Manufacturer" "KYOCERA AVX"
			(at 0 0 90)
			(unlocked yes)
			(layer "F.Fab")
			(hide yes)
			(effects
				(font
					(size 1 1)
					(thickness 0.15)
				)
			)
		)
		(property "License" "Apache-2.0"
			(at 0 0 90)
			(unlocked yes)
			(layer "F.Fab")
			(hide yes)
			(effects
				(font
					(size 1 1)
					(thickness 0.15)
				)
			)
		)
		(property "Author" "Antmicro"
			(at 0 0 90)
			(unlocked yes)
			(layer "F.Fab")
			(hide yes)
			(effects
				(font
					(size 1 1)
					(thickness 0.15)
				)
			)
		)
		(property "Val" "33p"
			(at 0 0 90)
			(unlocked yes)
			(layer "F.Fab")
			(hide yes)
			(effects
				(font
					(size 1 1)
					(thickness 0.15)
				)
			)
		)
		(property "Voltage" ""
			(at 0 0 90)
			(unlocked yes)
			(layer "F.Fab")
			(hide yes)
			(effects
				(font
					(size 1 1)
					(thickness 0.15)
				)
			)
		)
		(property "Dielectric" ""
			(at 0 0 90)
			(unlocked yes)
			(layer "F.Fab")
			(hide yes)
			(effects
				(font
					(size 1 1)
					(thickness 0.15)
				)
			)
		)
		(sheetname "/Power/")
		(sheetfile "power.kicad_sch")
		(attr smd exclude_from_pos_files exclude_from_bom dnp)
		(fp_rect
			(start -0.925 -0.47)
			(end 0.925 0.47)
			(stroke
				(width 0.05)
				(type default)
			)
			(fill no)
			(layer "F.CrtYd")
		)
		(fp_line
			(start 0.504 -0.25)
			(end 0.504 0.248)
			(stroke
				(width 0.15)
				(type solid)
			)
			(layer "F.Fab")
		)
		(fp_line
			(start -0.494 -0.25)
			(end 0.504 -0.25)
			(stroke
				(width 0.15)
				(type solid)
			)
			(layer "F.Fab")
		)
		(fp_line
			(start 0.504 0.248)
			(end -0.494 0.248)
			(stroke
				(width 0.15)
				(type solid)
			)
			(layer "F.Fab")
		)
		(fp_line
			(start -0.494 0.248)
			(end -0.494 -0.25)
			(stroke
				(width 0.15)
				(type solid)
			)
			(layer "F.Fab")
		)
		(pad "1" smd roundrect
			(at -0.48 0 90)
			(size 0.59 0.64)
			(layers "F.Cu" "F.Mask" "F.Paste")
			(roundrect_rratio 0.25)
			(net 332 "/Power/1V0_FB")
			(pintype "passive")
		)
		(pad "2" smd roundrect
			(at 0.48 0 90)
			(size 0.59 0.64)
			(layers "F.Cu" "F.Mask" "F.Paste")
			(roundrect_rratio 0.25)
			(net 312 "/Power/+1V0_OUT")
			(pintype "passive")
		)
	)
	(footprint "antmicro-footprints:R_0402_1005Metric"
		(layer "F.Cu")
		(at 53.1 108.25 -90)
		(descr "Resistor SMD 0402")
		(tags "resistor SMD 0402")
		(property "Reference" "R24"
			(at -1.09 2.88 90)
			(layer "F.SilkS")
			(effects
				(font
					(size 0.7 0.7)
					(thickness 0.15)
				)
				(justify right top)
			)
		)
		(property "Value" "R_0R_0402"
			(at -1.011843 1.772046 90)
			(layer "F.Fab")
			(hide yes)
			(effects
				(font
					(size 0.7 0.7)
					(thickness 0.15)
				)
				(justify right top)
			)
		)
		(property "Datasheet" "https://industrial.panasonic.com/cdbs/www-data/pdf/RDA0000/AOA0000C301.pdf"
			(at 0 0 90)
			(layer "F.Fab")
			(hide yes)
			(effects
				(font
					(size 1.27 1.27)
					(thickness 0.15)
				)
			)
		)
		(property "Description" "SMD Chip Resistor, Jumper, 0 ohm, 100 mW, 0402 [1005 Metric], Thick Film, General Purpose"
			(at 0 0 90)
			(layer "F.Fab")
			(hide yes)
			(effects
				(font
					(size 1.27 1.27)
					(thickness 0.15)
				)
			)
		)
		(property "MPN" "ERJ2GE0R00X"
			(at 0 0 270)
			(unlocked yes)
			(layer "F.Fab")
			(hide yes)
			(effects
				(font
					(size 1 1)
					(thickness 0.15)
				)
			)
		)
		(property "Manufacturer" "Panasonic"
			(at 0 0 270)
			(unlocked yes)
			(layer "F.Fab")
			(hide yes)
			(effects
				(font
					(size 1 1)
					(thickness 0.15)
				)
			)
		)
		(property "License" "Apache-2.0"
			(at 0 0 270)
			(unlocked yes)
			(layer "F.Fab")
			(hide yes)
			(effects
				(font
					(size 1 1)
					(thickness 0.15)
				)
			)
		)
		(property "Author" "Antmicro"
			(at 0 0 270)
			(unlocked yes)
			(layer "F.Fab")
			(hide yes)
			(effects
				(font
					(size 1 1)
					(thickness 0.15)
				)
			)
		)
		(property "Val" "0R"
			(at 0 0 270)
			(unlocked yes)
			(layer "F.Fab")
			(hide yes)
			(effects
				(font
					(size 1 1)
					(thickness 0.15)
				)
			)
		)
		(property "Tolerance" "~"
			(at 0 0 270)
			(unlocked yes)
			(layer "F.Fab")
			(hide yes)
			(effects
				(font
					(size 1 1)
					(thickness 0.15)
				)
			)
		)
		(property "Current" "1A"
			(at 0 0 270)
			(unlocked yes)
			(layer "F.Fab")
			(hide yes)
			(effects
				(font
					(size 1 1)
					(thickness 0.15)
				)
			)
		)
		(sheetname "/Power/")
		(sheetfile "power.kicad_sch")
		(attr smd)
		(fp_rect
			(start -0.925 -0.47)
			(end 0.925 0.47)
			(stroke
				(width 0.05)
				(type default)
			)
			(fill no)
			(layer "F.CrtYd")
		)
		(fp_rect
			(start -0.5 -0.25)
			(end 0.5 0.25)
			(stroke
				(width 0.15)
				(type solid)
			)
			(fill no)
			(layer "F.Fab")
		)
		(pad "1" smd roundrect
			(at -0.48 0 270)
			(size 0.59 0.64)
			(layers "F.Cu" "F.Mask" "F.Paste")
			(roundrect_rratio 0.25)
			(net 369 "/Power/1V88_PG")
			(pintype "passive")
		)
		(pad "2" smd roundrect
			(at 0.48 0 270)
			(size 0.59 0.64)
			(layers "F.Cu" "F.Mask" "F.Paste")
			(roundrect_rratio 0.25)
			(net 377 "/Power/1V0_EN")
			(pintype "passive")
		)
	)
	(footprint "antmicro-footprints:LED_0603_1608Metric_G"
		(layer "F.Cu")
		(at 54.35 127.449999 180)
		(descr "LED SMD 0603 Green")
		(tags "LED SMD 0603 Green")
		(property "Reference" "D16"
			(at -1.1 -0.750001 0)
			(layer "F.SilkS")
			(effects
				(font
					(size 0.7 0.7)
					(thickness 0.15)
				)
				(justify right top)
			)
		)
		(property "Value" "LED_G_0603_LG_L29K-G2J1-24-Z"
			(at -0.001 1.599 0)
			(layer "F.Fab")
			(hide yes)
			(effects
				(font
					(size 0.7 0.7)
					(thickness 0.15)
				)
				(justify right top)
			)
		)
		(property "Datasheet" "https://look.ams-osram.com/m/19ee86b3ae0ee95b/original/LG-L29K.pdf"
			(at 0 0 0)
			(layer "F.Fab")
			(hide yes)
			(effects
				(font
					(size 1.27 1.27)
					(thickness 0.15)
				)
			)
		)
		(property "Description" "LED, Green, SMD, 0603, 20 mA, 1.7 V, 570 nm"
			(at 0 0 0)
			(layer "F.Fab")
			(hide yes)
			(effects
				(font
					(size 1.27 1.27)
					(thickness 0.15)
				)
			)
		)
		(property "MPN" "LG L29K-G2J1-24-Z"
			(at 0 0 180)
			(unlocked yes)
			(layer "F.Fab")
			(hide yes)
			(effects
				(font
					(size 1 1)
					(thickness 0.15)
				)
			)
		)
		(property "Manufacturer" "OSRAM"
			(at 0 0 180)
			(unlocked yes)
			(layer "F.Fab")
			(hide yes)
			(effects
				(font
					(size 1 1)
					(thickness 0.15)
				)
			)
		)
		(property "Color" "Green"
			(at 0 0 180)
			(unlocked yes)
			(layer "F.Fab")
			(hide yes)
			(effects
				(font
					(size 1 1)
					(thickness 0.15)
				)
			)
		)
		(property "Author" "Antmicro"
			(at 0 0 180)
			(unlocked yes)
			(layer "F.Fab")
			(hide yes)
			(effects
				(font
					(size 1 1)
					(thickness 0.15)
				)
			)
		)
		(property "License" "Apache-2.0"
			(at 0 0 180)
			(unlocked yes)
			(layer "F.Fab")
			(hide yes)
			(effects
				(font
					(size 1 1)
					(thickness 0.15)
				)
			)
		)
		(sheetname "/Power/")
		(sheetfile "power.kicad_sch")
		(attr smd)
		(fp_line
			(start 0.22 0.35)
			(end -0.22 0.35)
			(stroke
				(width 0.15)
				(type solid)
			)
			(layer "F.SilkS")
		)
		(fp_line
			(start 0.22 -0.35)
			(end -0.22 -0.35)
			(stroke
				(width 0.15)
				(type solid)
			)
			(layer "F.SilkS")
		)
		(fp_line
			(start 0.105328 0.201008)
			(end 0.105328 -0.198992)
			(stroke
				(width 0.1)
				(type solid)
			)
			(layer "F.SilkS")
		)
		(fp_line
			(start 0.105328 0.201008)
			(end -0.094672 0.001008)
			(stroke
				(width 0.1)
				(type solid)
			)
			(layer "F.SilkS")
		)
		(fp_line
			(start 0.105328 0.001008)
			(end 0.24 0.001)
			(stroke
				(width 0.1)
				(type solid)
			)
			(layer "F.SilkS")
		)
		(fp_line
			(start -0.094672 0.201008)
			(end -0.094672 -0.198992)
			(stroke
				(width 0.1)
				(type solid)
			)
			(layer "F.SilkS")
		)
		(fp_line
			(start -0.094672 0.001008)
			(end 0.105328 -0.198992)
			(stroke
				(width 0.1)
				(type solid)
			)
			(layer "F.SilkS")
		)
		(fp_line
			(start -0.094672 0.001008)
			(end -0.24 0.001008)
			(stroke
				(width 0.1)
				(type solid)
			)
			(layer "F.SilkS")
		)
		(fp_line
			(start -1.18 -0.319)
			(end -1.18 0.321)
			(stroke
				(width 0.15)
				(type solid)
			)
			(layer "F.SilkS")
		)
		(fp_rect
			(start 1.25 0.65)
			(end -1.25 -0.65)
			(stroke
				(width 0.05)
				(type solid)
			)
			(fill no)
			(layer "F.CrtYd")
		)
		(fp_line
			(start 0.599 0)
			(end 0.201 0)
			(stroke
				(width 0.15)
				(type solid)
			)
			(layer "F.Fab")
		)
		(fp_line
			(start 0.201 0.2)
			(end 0.201 0)
			(stroke
				(width 0.15)
				(type solid)
			)
			(layer "F.Fab")
		)
		(fp_line
			(start 0.201 0)
			(end 0.201 -0.202)
			(stroke
				(width 0.15)
				(type solid)
			)
			(layer "F.Fab")
		)
		(fp_line
			(start 0.201 -0.202)
			(end -0.101 0)
			(stroke
				(width 0.15)
				(type solid)
			)
			(layer "F.Fab")
		)
		(fp_line
			(start -0.101 0)
			(end 0.201 0.2)
			(stroke
				(width 0.15)
				(type solid)
			)
			(layer "F.Fab")
		)
		(fp_line
			(start -0.199 0.2)
			(end -0.199 0.1)
			(stroke
				(width 0.15)
				(type solid)
			)
			(layer "F.Fab")
		)
		(fp_line
			(start -0.199 0)
			(end -0.597 0)
			(stroke
				(width 0.15)
				(type solid)
			)
			(layer "F.Fab")
		)
		(fp_line
			(start -0.199 -0.202)
			(end -0.199 0.1)
			(stroke
				(width 0.15)
				(type solid)
			)
			(layer "F.Fab")
		)
		(fp_rect
			(start 0.848 0.4)
			(end -0.85 -0.402)
			(stroke
				(width 0.15)
				(type solid)
			)
			(fill no)
			(layer "F.Fab")
		)
		(fp_text user "License: Apache-2.0"
			(at -1.4224 3.599 180)
			(layer "F.Fab")
			(effects
				(font
					(size 0.7 0.7)
					(thickness 0.15)
				)
				(justify left bottom)
			)
		)
		(fp_text user "${REFERENCE}"
			(at -1.4224 5.999 180)
			(layer "F.Fab")
			(effects
				(font
					(size 0.7 0.7)
					(thickness 0.15)
				)
				(justify left bottom)
			)
		)
		(fp_text user "Author: Antmicro"
			(at -1.4224 4.799 180)
			(layer "F.Fab")
			(effects
				(font
					(size 0.7 0.7)
					(thickness 0.15)
				)
				(justify left bottom)
			)
		)
		(pad "1" smd roundrect
			(at -0.7 0)
			(size 0.8 1)
			(layers "F.Cu" "F.Mask" "F.Paste")
			(roundrect_rratio 0.2)
			(net 415 "Net-(D16-C)")
			(pinfunction "C")
			(pintype "passive")
		)
		(pad "2" smd roundrect
			(at 0.7 0)
			(size 0.8 1)
			(layers "F.Cu" "F.Mask" "F.Paste")
			(roundrect_rratio 0.2)
			(net 255 "/Power/+3V3_OUT")
			(pinfunction "A")
			(pintype "passive")
		)
	)
	(footprint "antmicro-footprints:R_0402_1005Metric"
		(layer "F.Cu")
		(at 72.42 106.35)
		(descr "Resistor SMD 0402")
		(tags "resistor SMD 0402")
		(property "Reference" "R48"
			(at -1.08 -0.42 0)
			(layer "F.SilkS")
			(effects
				(font
					(size 0.7 0.7)
					(thickness 0.15)
				)
				(justify left bottom)
			)
		)
		(property "Value" "R_10R_0402"
			(at -1.011843 1.772047 0)
			(layer "F.Fab")
			(hide yes)
			(effects
				(font
					(size 0.7 0.7)
					(thickness 0.15)
				)
				(justify left bottom)
			)
		)
		(property "Datasheet" "https://www.bourns.com/docs/product-datasheets/cr.pdf"
			(at 0 0 0)
			(layer "F.Fab")
			(hide yes)
			(effects
				(font
					(size 1.27 1.27)
					(thickness 0.15)
				)
			)
		)
		(property "Description" "SMD Chip Resistor, 10 ohm, ± 1%, 62.5 mW, 0402 [1005 Metric], Thick Film, General Purpose"
			(at 0 0 0)
			(layer "F.Fab")
			(hide yes)
			(effects
				(font
					(size 1.27 1.27)
					(thickness 0.15)
				)
			)
		)
		(property "MPN" "CR0402-FX-10R0GLF"
			(at 0 0 0)
			(unlocked yes)
			(layer "F.Fab")
			(hide yes)
			(effects
				(font
					(size 1 1)
					(thickness 0.15)
				)
			)
		)
		(property "Manufacturer" "Bourns"
			(at 0 0 0)
			(unlocked yes)
			(layer "F.Fab")
			(hide yes)
			(effects
				(font
					(size 1 1)
					(thickness 0.15)
				)
			)
		)
		(property "License" "Apache-2.0"
			(at 0 0 0)
			(unlocked yes)
			(layer "F.Fab")
			(hide yes)
			(effects
				(font
					(size 1 1)
					(thickness 0.15)
				)
			)
		)
		(property "Author" "Antmicro"
			(at 0 0 0)
			(unlocked yes)
			(layer "F.Fab")
			(hide yes)
			(effects
				(font
					(size 1 1)
					(thickness 0.15)
				)
			)
		)
		(property "Val" "10R"
			(at 0 0 0)
			(unlocked yes)
			(layer "F.Fab")
			(hide yes)
			(effects
				(font
					(size 1 1)
					(thickness 0.15)
				)
			)
		)
		(property "Tolerance" "1%"
			(at 0 0 0)
			(unlocked yes)
			(layer "F.Fab")
			(hide yes)
			(effects
				(font
					(size 1 1)
					(thickness 0.15)
				)
			)
		)
		(sheetname "/X710-AT2 Misc/")
		(sheetfile "x710-at2-mics.kicad_sch")
		(attr smd)
		(fp_rect
			(start -0.925 -0.47)
			(end 0.925 0.47)
			(stroke
				(width 0.05)
				(type default)
			)
			(fill no)
			(layer "F.CrtYd")
		)
		(fp_rect
			(start -0.5 -0.25)
			(end 0.5 0.25)
			(stroke
				(width 0.15)
				(type solid)
			)
			(fill no)
			(layer "F.Fab")
		)
		(pad "1" smd roundrect
			(at -0.48 0)
			(size 0.59 0.64)
			(layers "F.Cu" "F.Mask" "F.Paste")
			(roundrect_rratio 0.25)
			(net 77 "/X710-AT2 Misc/50MHZ_XTAL_R.-")
			(pintype "passive")
		)
		(pad "2" smd roundrect
			(at 0.48 0)
			(size 0.59 0.64)
			(layers "F.Cu" "F.Mask" "F.Paste")
			(roundrect_rratio 0.25)
			(net 191 "/X710-AT2 Misc/50MHZ_XTAL.-")
			(pintype "passive")
		)
	)
	(footprint "antmicro-footprints:C_0603_1608Metric"
		(layer "F.Cu")
		(at 97.9 99.3 180)
		(descr "Capacitor SMD 0603")
		(tags "capacitor 0603")
		(property "Reference" "C147"
			(at -3.75 0.35 0)
			(layer "F.SilkS")
			(effects
				(font
					(size 0.7 0.7)
					(thickness 0.15)
				)
				(justify left top)
			)
		)
		(property "Value" "C_10u_10V_X7R_0603"
			(at -1.42757 1.770288 0)
			(layer "F.Fab")
			(hide yes)
			(effects
				(font
					(size 0.7 0.7)
					(thickness 0.15)
				)
				(justify right top)
			)
		)
		(property "Datasheet" "https://www.murata.com/products/productdetail?partno=GRM188Z71A106KA73%23"
			(at 0 0 0)
			(layer "F.Fab")
			(hide yes)
			(effects
				(font
					(size 1.27 1.27)
					(thickness 0.15)
				)
			)
		)
		(property "Description" "SMD Multilayer Ceramic Capacitor,  10µF, 10V, 0603, ±10%, X7R"
			(at 0 0 0)
			(layer "F.Fab")
			(hide yes)
			(effects
				(font
					(size 1.27 1.27)
					(thickness 0.15)
				)
			)
		)
		(property "MPN" "GRM188Z71A106KA73D"
			(at 0 0 180)
			(unlocked yes)
			(layer "F.Fab")
			(hide yes)
			(effects
				(font
					(size 1 1)
					(thickness 0.15)
				)
			)
		)
		(property "Val" "10u"
			(at 0 0 180)
			(unlocked yes)
			(layer "F.Fab")
			(hide yes)
			(effects
				(font
					(size 1 1)
					(thickness 0.15)
				)
			)
		)
		(property "Voltage" "10V"
			(at 0 0 180)
			(unlocked yes)
			(layer "F.Fab")
			(hide yes)
			(effects
				(font
					(size 1 1)
					(thickness 0.15)
				)
			)
		)
		(property "Dielectric" "X7R"
			(at 0 0 180)
			(unlocked yes)
			(layer "F.Fab")
			(hide yes)
			(effects
				(font
					(size 1 1)
					(thickness 0.15)
				)
			)
		)
		(property "Manufacturer" "Murata"
			(at 0 0 180)
			(unlocked yes)
			(layer "F.Fab")
			(hide yes)
			(effects
				(font
					(size 1 1)
					(thickness 0.15)
				)
			)
		)
		(property "License" "Apache-2.0"
			(at 0 0 180)
			(unlocked yes)
			(layer "F.Fab")
			(hide yes)
			(effects
				(font
					(size 1 1)
					(thickness 0.15)
				)
			)
		)
		(property "Author" "Antmicro"
			(at 0 0 180)
			(unlocked yes)
			(layer "F.Fab")
			(hide yes)
			(effects
				(font
					(size 1 1)
					(thickness 0.15)
				)
			)
		)
		(sheetname "/X710-AT2 power/")
		(sheetfile "x710-at2-power.kicad_sch")
		(attr smd)
		(fp_line
			(start -0.15 0.4)
			(end 0.15 0.4)
			(stroke
				(width 0.15)
				(type solid)
			)
			(layer "F.SilkS")
		)
		(fp_line
			(start -0.15 -0.4)
			(end 0.15 -0.4)
			(stroke
				(width 0.15)
				(type solid)
			)
			(layer "F.SilkS")
		)
		(fp_rect
			(start -1.25 -0.65)
			(end 1.25 0.65)
			(stroke
				(width 0.05)
				(type solid)
			)
			(fill no)
			(layer "F.CrtYd")
		)
		(fp_rect
			(start -0.8 -0.4)
			(end 0.8 0.4)
			(stroke
				(width 0.15)
				(type solid)
			)
			(fill no)
			(layer "F.Fab")
		)
		(pad "1" smd roundrect
			(at -0.7 0 180)
			(size 0.8 1)
			(layers "F.Cu" "F.Mask" "F.Paste")
			(roundrect_rratio 0.2)
			(net 28 "GND")
			(pintype "passive")
		)
		(pad "2" smd roundrect
			(at 0.7 0 180)
			(size 0.8 1)
			(layers "F.Cu" "F.Mask" "F.Paste")
			(roundrect_rratio 0.2)
			(net 7 "+3V3")
			(pintype "passive")
		)
	)
)
